(kicad_pcb
	(version 20260206)
	(generator "pcbnew")
	(generator_version "10.0")
	(general
		(thickness 1.6)
		(legacy_teardrops no)
	)
	(paper "A4")
	(title_block
		(title "v1-pdb — T6M_PDB_D_0927_0900.brd")
		(comment 1 "Open CloudServer (Microsoft) / footprints 301-306 of 321")
	)
	(layers
		(0 "F.Cu" signal "TOP")
		(4 "In1.Cu" signal "GND")
		(6 "In2.Cu" signal "IN1")
		(8 "In3.Cu" signal "VCC")
		(10 "In4.Cu" signal "VCC1")
		(12 "In5.Cu" signal "IN2")
		(14 "In6.Cu" signal "GND1")
		(2 "B.Cu" signal "BOTTOM")
		(9 "F.Adhes" user "F.Adhesive")
		(11 "B.Adhes" user "B.Adhesive")
		(13 "F.Paste" user "Package Geometry/Pastemask Top")
		(15 "B.Paste" user "Package Geometry/Pastemask Bottom")
		(5 "F.SilkS" user "Ref Des/Silkscreen Top")
		(7 "B.SilkS" user "Ref Des/Silkscreen Bottom")
		(1 "F.Mask" user "Board Geometry/Soldermask Top")
		(3 "B.Mask" user "Board Geometry/Soldermask Bottom")
		(17 "Dwgs.User" user "User.Drawings")
		(19 "Cmts.User" user "User.Comments")
		(21 "Eco1.User" user "User.Eco1")
		(23 "Eco2.User" user "User.Eco2")
		(25 "Edge.Cuts" user "Board Geometry/Outline")
		(27 "Margin" user)
		(31 "F.CrtYd" user "Package Geometry/Place Bound Top")
		(29 "B.CrtYd" user "Package Geometry/Place Bound Bottom")
		(35 "F.Fab" user "Ref Des/Assembly Top")
		(33 "B.Fab" user "Ref Des/Assembly Bottom")
	)
	(footprint ""
		(layer "F.Cu")
		(at 2.439924 -373.875046 90)
		(property "Reference" "J31"
			(at -1.76022 4.875022 90)
			(unlocked yes)
			(layer "F.SilkS")
			(effects
				(font
					(size 0.7874 0.5842)
					(thickness 0.1524)
				)
				(justify left)
			)
		)
		(property "Value" ""
			(at 0 0 90)
			(layer "F.Fab")
			(effects
				(font
					(size 1.27 1.27)
				)
			)
		)
		(duplicate_pad_numbers_are_jumpers no)
		(fp_line
			(start 1.849882 -1.999996)
			(end -3.02006 -1.999996)
			(stroke
				(width 0.1524)
				(type default)
			)
			(layer "F.SilkS")
		)
		(fp_line
			(start -3.02006 -1.999996)
			(end -3.02006 3.999992)
			(stroke
				(width 0.1524)
				(type default)
			)
			(layer "F.SilkS")
		)
		(fp_line
			(start 1.35001 -1.500124)
			(end -2.519934 -1.500124)
			(stroke
				(width 0.1524)
				(type default)
			)
			(layer "F.SilkS")
		)
		(fp_line
			(start -2.519934 -1.500124)
			(end -2.519934 3.50012)
			(stroke
				(width 0.1524)
				(type default)
			)
			(layer "F.SilkS")
		)
		(fp_line
			(start 1.849882 0.500126)
			(end 1.35001 0.500126)
			(stroke
				(width 0.1524)
				(type default)
			)
			(layer "F.SilkS")
		)
		(fp_line
			(start 1.35001 0.500126)
			(end 1.35001 -1.500124)
			(stroke
				(width 0.1524)
				(type default)
			)
			(layer "F.SilkS")
		)
		(fp_line
			(start 1.35001 1.500124)
			(end 1.849882 1.500124)
			(stroke
				(width 0.1524)
				(type default)
			)
			(layer "F.SilkS")
		)
		(fp_line
			(start 1.35001 3.50012)
			(end 1.35001 1.500124)
			(stroke
				(width 0.1524)
				(type default)
			)
			(layer "F.SilkS")
		)
		(fp_line
			(start -2.519934 3.50012)
			(end 1.35001 3.50012)
			(stroke
				(width 0.1524)
				(type default)
			)
			(layer "F.SilkS")
		)
		(fp_line
			(start 1.849882 3.999992)
			(end 1.849882 -1.999996)
			(stroke
				(width 0.1524)
				(type default)
			)
			(layer "F.SilkS")
		)
		(fp_line
			(start -3.02006 3.999992)
			(end 1.849882 3.999992)
			(stroke
				(width 0.1524)
				(type default)
			)
			(layer "F.SilkS")
		)
		(fp_poly
			(pts
				(xy 2.01041 0) (xy 3.06959 -0.52959) (xy 3.06959 0.52959)
			)
			(stroke
				(width 0)
				(type default)
			)
			(fill yes)
			(layer "F.SilkS")
		)
		(fp_poly
			(pts
				(xy -0.8382 2.8194) (xy 0.8382 2.8194) (xy 0.8382 -0.8382) (xy -0.8382 -0.8382)
			)
			(stroke
				(width 0)
				(type default)
			)
			(fill no)
			(layer "B.CrtYd")
		)
		(fp_poly
			(pts
				(xy -3.02006 3.999992) (xy 1.849882 3.999992) (xy 1.849882 -1.999996) (xy -3.02006 -1.999996)
			)
			(stroke
				(width 0)
				(type default)
			)
			(fill no)
			(layer "F.CrtYd")
		)
		(fp_line
			(start 1.849882 -1.999996)
			(end -3.02006 -1.999996)
			(stroke
				(width 0.1)
				(type default)
			)
			(layer "F.Fab")
		)
		(fp_line
			(start -3.02006 -1.999996)
			(end -3.02006 3.999992)
			(stroke
				(width 0.1)
				(type default)
			)
			(layer "F.Fab")
		)
		(fp_line
			(start 1.849882 3.999992)
			(end 1.849882 -1.999996)
			(stroke
				(width 0.1)
				(type default)
			)
			(layer "F.Fab")
		)
		(fp_line
			(start -3.02006 3.999992)
			(end 1.849882 3.999992)
			(stroke
				(width 0.1)
				(type default)
			)
			(layer "F.Fab")
		)
		(fp_poly
			(pts
				(xy 2.01041 0) (xy 3.06959 -0.52959) (xy 3.06959 0.52959)
			)
			(stroke
				(width 0)
				(type default)
			)
			(fill yes)
			(layer "F.Fab")
		)
		(fp_text user "2"
			(at 2.5527 2.16535 90)
			(unlocked yes)
			(layer "F.SilkS")
			(effects
				(font
					(size 0.7874 0.5842)
					(thickness 0.1524)
				)
			)
		)
		(fp_text user "1"
			(at 1.2192 0.00127 90)
			(unlocked yes)
			(layer "B.SilkS")
			(effects
				(font
					(size 0.7874 0.5842)
					(thickness 0.1524)
				)
				(justify mirror)
			)
		)
		(fp_text user "2"
			(at 1.2192 2.001266 90)
			(unlocked yes)
			(layer "B.SilkS")
			(effects
				(font
					(size 0.7874 0.5842)
					(thickness 0.1524)
				)
				(justify mirror)
			)
		)
		(fp_text user "1"
			(at 1.2192 0.00127 90)
			(unlocked yes)
			(layer "B.Fab")
			(effects
				(font
					(size 0.7874 0.5842)
					(thickness 0.1524)
				)
				(justify mirror)
			)
		)
		(fp_text user "2"
			(at 1.2192 2.001266 90)
			(unlocked yes)
			(layer "B.Fab")
			(effects
				(font
					(size 0.7874 0.5842)
					(thickness 0.1524)
				)
				(justify mirror)
			)
		)
		(fp_text user "2"
			(at 2.5527 2.16535 90)
			(unlocked yes)
			(layer "F.Fab")
			(effects
				(font
					(size 0.7874 0.5842)
					(thickness 0.1524)
				)
			)
		)
		(pad "1" thru_hole rect
			(at 0 0 90)
			(size 1.524 1.524)
			(drill 1.016)
			(layers "*.Cu" "*.Mask")
			(remove_unused_layers no)
			(net "POWER_SW2_PWR_CTR_12V")
			(clearance 0)
			(padstack
				(mode front_inner_back)
				(layer "Inner"
					(shape circle)
					(size 1.524 1.524)
					(clearance 0)
				)
				(layer "B.Cu"
					(shape rect)
					(size 1.524 1.524)
					(clearance 0)
				)
			)
		)
		(pad "2" thru_hole circle
			(at 0 1.999996 90)
			(size 1.524 1.524)
			(drill 1.016)
			(layers "*.Cu" "*.Mask")
			(remove_unused_layers no)
			(net "GND")
			(clearance 0)
		)
	)
	(footprint ""
		(layer "F.Cu")
		(at 25.931622 -98.10369)
		(property "Reference" "R66"
			(at -4.080256 -0.075692 0)
			(unlocked yes)
			(layer "F.SilkS")
			(effects
				(font
					(size 0.7874 0.5842)
					(thickness 0.1524)
				)
				(justify left)
			)
		)
		(property "Value" ""
			(at 0 0 0)
			(layer "F.Fab")
			(effects
				(font
					(size 1.27 1.27)
				)
			)
		)
		(duplicate_pad_numbers_are_jumpers no)
		(fp_line
			(start -0.7874 -0.4064)
			(end 0.7874 -0.4064)
			(stroke
				(width 0.1524)
				(type default)
			)
			(layer "F.SilkS")
		)
		(fp_line
			(start -0.7874 0.4064)
			(end -0.7874 -0.4064)
			(stroke
				(width 0.1524)
				(type default)
			)
			(layer "F.SilkS")
		)
		(fp_line
			(start 0.7874 -0.4064)
			(end 0.7874 0.4064)
			(stroke
				(width 0.1524)
				(type default)
			)
			(layer "F.SilkS")
		)
		(fp_line
			(start 0.7874 0.4064)
			(end -0.7874 0.4064)
			(stroke
				(width 0.1524)
				(type default)
			)
			(layer "F.SilkS")
		)
		(fp_poly
			(pts
				(xy -0.508 0.2794) (xy -0.508 0.2286) (xy -0.635 0.2286) (xy -0.635 -0.254) (xy -0.5334 -0.254)
				(xy -0.5334 -0.2794) (xy 0.5334 -0.2794) (xy 0.5334 -0.254) (xy 0.635 -0.254) (xy 0.635 0.254) (xy 0.5334 0.254)
				(xy 0.5334 0.2794)
			)
			(stroke
				(width 0)
				(type default)
			)
			(fill no)
			(layer "F.CrtYd")
		)
		(pad "1" smd rect
			(at 0.40005 0)
			(size 0.4572 0.508)
			(layers "F.Cu" "F.Mask" "F.Paste")
			(net "PSU2_PS_KILL")
		)
		(pad "2" smd rect
			(at -0.40005 0)
			(size 0.4572 0.508)
			(layers "F.Cu" "F.Mask" "F.Paste")
			(net "P12V_STBY")
		)
	)
	(footprint ""
		(layer "F.Cu")
		(at 91.399868 -375.61012)
		(property "Reference" "H23"
			(at -5.1308 -5.23113 0)
			(unlocked yes)
			(layer "F.SilkS")
			(effects
				(font
					(size 0.7874 0.5842)
					(thickness 0.1524)
				)
				(justify left)
			)
		)
		(property "Value" ""
			(at 0 0 0)
			(layer "F.Fab")
			(effects
				(font
					(size 1.27 1.27)
				)
			)
		)
		(duplicate_pad_numbers_are_jumpers no)
		(fp_circle
			(center 0 0)
			(end 4.826 0)
			(stroke
				(width 0.1524)
				(type default)
			)
			(fill no)
			(layer "F.SilkS")
		)
		(fp_circle
			(center 0 0)
			(end 4.826 0)
			(stroke
				(width 0.1524)
				(type default)
			)
			(fill no)
			(layer "B.SilkS")
		)
		(fp_poly
			(pts
				(arc
					(start 0 4.0132)
					(mid 0 -4.0132)
					(end 0 4.0132)
				)
			)
			(stroke
				(width 0)
				(type default)
			)
			(fill no)
			(layer "F.CrtYd")
		)
		(pad "" np_thru_hole circle
			(at 0 0)
			(size 8.001 8.001)
			(drill 8.001)
			(layers "*.Cu" "*.Mask")
			(clearance 0.381)
			(thermal_gap 0.381)
		)
		(zone
			(layers "F.Cu" "B.Cu" "In1.Cu" "In2.Cu" "In3.Cu" "In4.Cu" "In5.Cu" "In6.Cu")
			(hatch none 0.5)
			(connect_pads
				(clearance 0)
			)
			(min_thickness 0.25)
			(keepout
				(tracks not_allowed)
				(vias allowed)
				(pads allowed)
				(copperpour not_allowed)
				(footprints allowed)
			)
			(placement
				(enabled no)
				(sheetname "")
			)
			(fill
				(thermal_gap 0.5)
				(thermal_bridge_width 0.5)
				(island_removal_mode 0)
			)
			(polygon
				(pts
					(arc
						(start 91.399868 -371.08892)
						(mid 91.399868 -380.13132)
						(end 91.399868 -371.08892)
					)
				)
			)
		)
	)
	(footprint ""
		(layer "F.Cu")
		(at 39.97325 -192.216278 180)
		(property "Reference" "R10"
			(at -1.626616 -0.081026 0)
			(unlocked yes)
			(layer "F.SilkS")
			(effects
				(font
					(size 0.7874 0.5842)
					(thickness 0.1524)
				)
				(justify left)
			)
		)
		(property "Value" ""
			(at 0 0 180)
			(layer "F.Fab")
			(effects
				(font
					(size 1.27 1.27)
				)
			)
		)
		(duplicate_pad_numbers_are_jumpers no)
		(fp_line
			(start 0.7874 0.4064)
			(end -0.7874 0.4064)
			(stroke
				(width 0.1524)
				(type default)
			)
			(layer "F.SilkS")
		)
		(fp_line
			(start 0.7874 -0.4064)
			(end 0.7874 0.4064)
			(stroke
				(width 0.1524)
				(type default)
			)
			(layer "F.SilkS")
		)
		(fp_line
			(start -0.7874 0.4064)
			(end -0.7874 -0.4064)
			(stroke
				(width 0.1524)
				(type default)
			)
			(layer "F.SilkS")
		)
		(fp_line
			(start -0.7874 -0.4064)
			(end 0.7874 -0.4064)
			(stroke
				(width 0.1524)
				(type default)
			)
			(layer "F.SilkS")
		)
		(fp_poly
			(pts
				(xy -0.508 0.2794) (xy -0.508 0.2286) (xy -0.635 0.2286) (xy -0.635 -0.254) (xy -0.5334 -0.254)
				(xy -0.5334 -0.2794) (xy 0.5334 -0.2794) (xy 0.5334 -0.254) (xy 0.635 -0.254) (xy 0.635 0.254) (xy 0.5334 0.254)
				(xy 0.5334 0.2794)
			)
			(stroke
				(width 0)
				(type default)
			)
			(fill no)
			(layer "F.CrtYd")
		)
		(pad "1" smd rect
			(at 0.40005 0 180)
			(size 0.4572 0.508)
			(layers "F.Cu" "F.Mask" "F.Paste")
			(net "PSU3_RETURN")
		)
		(pad "2" smd rect
			(at -0.40005 0 180)
			(size 0.4572 0.508)
			(layers "F.Cu" "F.Mask" "F.Paste")
			(net "GND")
		)
	)
	(footprint ""
		(layer "F.Cu")
		(at 74.798682 -15.447772 -90)
		(property "Reference" "C1"
			(at -2.757424 -0.074422 90)
			(unlocked yes)
			(layer "F.SilkS")
			(effects
				(font
					(size 0.7874 0.5842)
					(thickness 0.1524)
				)
			)
		)
		(property "Value" ""
			(at 0 0 270)
			(layer "F.Fab")
			(effects
				(font
					(size 1.27 1.27)
				)
			)
		)
		(duplicate_pad_numbers_are_jumpers no)
		(fp_line
			(start -1.2954 0.5842)
			(end -1.2954 -0.5842)
			(stroke
				(width 0.1524)
				(type default)
			)
			(layer "F.SilkS")
		)
		(fp_line
			(start 1.2954 0.5842)
			(end -1.2954 0.5842)
			(stroke
				(width 0.1524)
				(type default)
			)
			(layer "F.SilkS")
		)
		(fp_line
			(start -1.2954 -0.5842)
			(end 1.2954 -0.5842)
			(stroke
				(width 0.1524)
				(type default)
			)
			(layer "F.SilkS")
		)
		(fp_line
			(start 0 -0.5842)
			(end 0 0.5842)
			(stroke
				(width 0.1524)
				(type default)
			)
			(layer "F.SilkS")
		)
		(fp_line
			(start 1.2954 -0.5842)
			(end 1.2954 0.5842)
			(stroke
				(width 0.1524)
				(type default)
			)
			(layer "F.SilkS")
		)
		(fp_poly
			(pts
				(xy 0.8636 -0.4572) (xy 0.8636 -0.3556) (xy 1.143 -0.3556) (xy 1.143 0.3556) (xy 0.8636 0.3556)
				(xy 0.8636 0.4572) (xy -0.8636 0.4572) (xy -0.8636 0.3556) (xy -1.143 0.3556) (xy -1.143 -0.3556)
				(xy -0.8636 -0.3556) (xy -0.8636 -0.4572)
			)
			(stroke
				(width 0)
				(type default)
			)
			(fill no)
			(layer "F.CrtYd")
		)
		(fp_line
			(start -0.884936 0.504952)
			(end -0.884936 -0.504952)
			(stroke
				(width 0.1)
				(type default)
			)
			(layer "F.Fab")
		)
		(fp_line
			(start 0.884936 0.504952)
			(end -0.884936 0.504952)
			(stroke
				(width 0.1)
				(type default)
			)
			(layer "F.Fab")
		)
		(fp_line
			(start -0.884936 -0.504952)
			(end 0.884936 -0.504952)
			(stroke
				(width 0.1)
				(type default)
			)
			(layer "F.Fab")
		)
		(fp_line
			(start 0.884936 -0.504952)
			(end 0.884936 0.504952)
			(stroke
				(width 0.1)
				(type default)
			)
			(layer "F.Fab")
		)
		(pad "1" smd rect
			(at 0.7366 0)
			(size 0.7112 0.8128)
			(layers "F.Cu" "F.Mask" "F.Paste")
			(net "P12V")
		)
		(pad "2" smd rect
			(at -0.7366 0)
			(size 0.7112 0.8128)
			(layers "F.Cu" "F.Mask" "F.Paste")
			(net "GND")
		)
	)
	(footprint ""
		(layer "F.Cu")
		(at 25.874472 -367.771426 180)
		(property "Reference" "R53"
			(at 3.856228 0.385064 0)
			(unlocked yes)
			(layer "F.SilkS")
			(effects
				(font
					(size 0.7874 0.5842)
					(thickness 0.1524)
				)
				(justify left)
			)
		)
		(property "Value" ""
			(at 0 0 180)
			(layer "F.Fab")
			(effects
				(font
					(size 1.27 1.27)
				)
			)
		)
		(duplicate_pad_numbers_are_jumpers no)
		(fp_line
			(start 0.7874 0.4064)
			(end -0.7874 0.4064)
			(stroke
				(width 0.1524)
				(type default)
			)
			(layer "F.SilkS")
		)
		(fp_line
			(start 0.7874 -0.4064)
			(end 0.7874 0.4064)
			(stroke
				(width 0.1524)
				(type default)
			)
			(layer "F.SilkS")
		)
		(fp_line
			(start -0.7874 0.4064)
			(end -0.7874 -0.4064)
			(stroke
				(width 0.1524)
				(type default)
			)
			(layer "F.SilkS")
		)
		(fp_line
			(start -0.7874 -0.4064)
			(end 0.7874 -0.4064)
			(stroke
				(width 0.1524)
				(type default)
			)
			(layer "F.SilkS")
		)
		(fp_poly
			(pts
				(xy -0.508 0.2794) (xy -0.508 0.2286) (xy -0.635 0.2286) (xy -0.635 -0.254) (xy -0.5334 -0.254)
				(xy -0.5334 -0.2794) (xy 0.5334 -0.2794) (xy 0.5334 -0.254) (xy 0.635 -0.254) (xy 0.635 0.254) (xy 0.5334 0.254)
				(xy 0.5334 0.2794)
			)
			(stroke
				(width 0)
				(type default)
			)
			(fill no)
			(layer "F.CrtYd")
		)
		(pad "1" smd rect
			(at 0.40005 0 180)
			(size 0.4572 0.508)
			(layers "F.Cu" "F.Mask" "F.Paste")
			(net "GND")
		)
		(pad "2" smd rect
			(at -0.40005 0 180)
			(size 0.4572 0.508)
			(layers "F.Cu" "F.Mask" "F.Paste")
			(net "PSU5_PS_ON_N")
		)
	)
)
